(kicad_pcb
	(version 20260206)
	(generator "pcbnew")
	(generator_version "10.0")
	(general
		(thickness 1.6)
		(legacy_teardrops no)
	)
	(paper "A4")
	(title_block
		(title "panther-plus-userver — 13130-1b_20150205.brd")
		(comment 1 "Honey Badger (Wiwynn) / footprint 624 of 1509 (DIMM4), pads 114-120 of 210")
	)
	(layers
		(0 "F.Cu" signal "TOP")
		(4 "In1.Cu" signal "L2")
		(6 "In2.Cu" signal "L3")
		(8 "In3.Cu" signal "L4")
		(10 "In4.Cu" signal "L5")
		(12 "In5.Cu" signal "L6")
		(14 "In6.Cu" signal "L7")
		(16 "In7.Cu" signal "L8")
		(18 "In8.Cu" signal "L9")
		(20 "In9.Cu" signal "L10")
		(22 "In10.Cu" signal "L11")
		(2 "B.Cu" signal "BOTTOM")
		(9 "F.Adhes" user "F.Adhesive")
		(11 "B.Adhes" user "B.Adhesive")
		(13 "F.Paste" user "Package Geometry/Pastemask Top")
		(15 "B.Paste" user "Package Geometry/Pastemask Bottom")
		(5 "F.SilkS" user "Ref Des/Silkscreen Top")
		(7 "B.SilkS" user "Ref Des/Silkscreen Bottom")
		(1 "F.Mask" user "Board Geometry/Soldermask Top")
		(3 "B.Mask" user "Board Geometry/Soldermask Bottom")
		(17 "Dwgs.User" user "User.Drawings")
		(19 "Cmts.User" user "User.Comments")
		(21 "Eco1.User" user "User.Eco1")
		(23 "Eco2.User" user "User.Eco2")
		(25 "Edge.Cuts" user "Board Geometry/Outline")
		(27 "Margin" user)
		(31 "F.CrtYd" user "Package Geometry/Place Bound Top")
		(29 "B.CrtYd" user "Package Geometry/Place Bound Bottom")
		(35 "F.Fab" user "Ref Des/Assembly Top")
		(33 "B.Fab" user "Ref Des/Assembly Bottom")
	)
	(footprint ""
		(layer "F.Cu")
		(at 159.999934 -5.790692)
		(property "Reference" "DIMM4"
			(at 0 0 0)
			(layer "F.SilkS")
			(hide yes)
			(effects
				(font
					(size 1.27 1.27)
				)
			)
		)
		(property "Value" "DDR3-204P-174-COLAY-1-GP"
			(at -40.682164 -17.468088 0)
			(unlocked yes)
			(layer "F.Fab")
			(hide yes)
			(effects
				(font
					(size 1.016 1.016)
					(thickness 0.1524)
				)
			)
		)
		(property "Device Type" "AS0A626-H8SN-7H-COLAY-1"
			(at -40.682164 -18.992088 0)
			(unlocked yes)
			(layer "F.Fab")
			(hide yes)
			(effects
				(font
					(size 1.016 1.016)
					(thickness 0.1524)
				)
			)
		)
		(duplicate_pad_numbers_are_jumpers no)
		(pad "112" smd custom
			(at 4.05003 -4.106672)
			(size 0.1143 0.1143)
			(layers "F.Cu" "F.Mask" "F.Paste")
			(net "M_B_CK_DP3")
			(options
				(clearance outline)
				(anchor circle)
			)
			(primitives
				(gr_poly
					(pts
						(xy 0 0.9017) (xy -0.03175 0.89916) (xy -0.0635 0.889) (xy -0.09144 0.87376) (xy -0.11684 0.85344)
						(xy -0.13716 0.82804) (xy -0.1524 0.8001) (xy -0.16256 0.76835) (xy -0.1651 0.7366) (xy -0.1651 0.19685)
						(xy -0.17272 0.18923) (xy -0.17907 0.18034) (xy -0.18669 0.17145) (xy -0.19177 0.16256) (xy -0.19812 0.15367)
						(xy -0.20828 0.13335) (xy -0.21971 0.10287) (xy -0.22225 0.09271) (xy -0.22479 0.08128) (xy -0.22606 0.07112)
						(xy -0.2286 0.05969) (xy -0.2286 0.01651) (xy -0.22606 0.00508) (xy -0.22479 -0.00508) (xy -0.22225 -0.01651)
						(xy -0.21971 -0.02667) (xy -0.20828 -0.05715) (xy -0.19812 -0.07747) (xy -0.19177 -0.08636) (xy -0.18669 -0.09525)
						(xy -0.17907 -0.10414) (xy -0.17272 -0.11303) (xy -0.1651 -0.12065) (xy -0.1651 -0.7366) (xy -0.16256 -0.76835)
						(xy -0.1524 -0.8001) (xy -0.13716 -0.82804) (xy -0.11684 -0.85344) (xy -0.09144 -0.87376) (xy -0.0635 -0.889)
						(xy -0.03175 -0.89916) (xy 0 -0.9017) (xy 0.03175 -0.89916) (xy 0.0635 -0.889) (xy 0.09144 -0.87376)
						(xy 0.11684 -0.85344) (xy 0.13716 -0.82804) (xy 0.1524 -0.8001) (xy 0.16256 -0.76835) (xy 0.1651 -0.7366)
						(xy 0.1651 -0.11938) (xy 0.17272 -0.11176) (xy 0.19812 -0.0762) (xy 0.2032 -0.06604) (xy 0.20701 -0.05715)
						(xy 0.21209 -0.04699) (xy 0.2159 -0.03683) (xy 0.21844 -0.02667) (xy 0.22225 -0.01524) (xy 0.22352 -0.00508)
						(xy 0.22606 0.00508) (xy 0.22733 0.01651) (xy 0.22733 0.02667) (xy 0.2286 0.0381) (xy 0.22733 0.04953)
						(xy 0.22733 0.05969) (xy 0.22606 0.07112) (xy 0.22352 0.08128) (xy 0.22225 0.09144) (xy 0.21844 0.10287)
						(xy 0.2159 0.11303) (xy 0.21209 0.12319) (xy 0.20701 0.13335) (xy 0.2032 0.14224) (xy 0.19812 0.1524)
						(xy 0.17272 0.18796) (xy 0.1651 0.19558) (xy 0.1651 0.7366) (xy 0.16256 0.76835) (xy 0.1524 0.8001)
						(xy 0.13716 0.82804) (xy 0.11684 0.85344) (xy 0.09144 0.87376) (xy 0.0635 0.889) (xy 0.03175 0.89916)
					)
					(width 0)
					(fill yes)
				)
			)
		)
		(pad "113" smd custom
			(at 4.350004 4.106672)
			(size 0.1143 0.1143)
			(layers "F.Cu" "F.Mask" "F.Paste")
			(net "M_B_CK_DN2")
			(options
				(clearance outline)
				(anchor circle)
			)
			(primitives
				(gr_poly
					(pts
						(xy 0 0.9017) (xy -0.03175 0.89916) (xy -0.0635 0.889) (xy -0.09144 0.87376) (xy -0.11684 0.85344)
						(xy -0.13716 0.82804) (xy -0.1524 0.8001) (xy -0.16256 0.76835) (xy -0.1651 0.7366) (xy -0.1651 -0.13462)
						(xy -0.17272 -0.14224) (xy -0.19812 -0.1778) (xy -0.2032 -0.18796) (xy -0.20701 -0.19685) (xy -0.21209 -0.20701)
						(xy -0.2159 -0.21717) (xy -0.21844 -0.22733) (xy -0.22225 -0.23876) (xy -0.22352 -0.24892) (xy -0.22606 -0.25908)
						(xy -0.22733 -0.27051) (xy -0.22733 -0.28067) (xy -0.2286 -0.2921) (xy -0.22733 -0.30353) (xy -0.22733 -0.31369)
						(xy -0.22606 -0.32512) (xy -0.22352 -0.33528) (xy -0.22225 -0.34544) (xy -0.21844 -0.35687) (xy -0.2159 -0.36703)
						(xy -0.21209 -0.37719) (xy -0.20701 -0.38735) (xy -0.2032 -0.39624) (xy -0.19812 -0.4064) (xy -0.17272 -0.44196)
						(xy -0.1651 -0.44958) (xy -0.1651 -0.7366) (xy -0.16256 -0.76835) (xy -0.1524 -0.8001) (xy -0.13716 -0.82804)
						(xy -0.11684 -0.85344) (xy -0.09144 -0.87376) (xy -0.0635 -0.889) (xy -0.03175 -0.89916) (xy 0 -0.9017)
						(xy 0.03175 -0.89916) (xy 0.0635 -0.889) (xy 0.09144 -0.87376) (xy 0.11684 -0.85344) (xy 0.13716 -0.82804)
						(xy 0.1524 -0.8001) (xy 0.16256 -0.76835) (xy 0.1651 -0.7366) (xy 0.1651 -0.44958) (xy 0.17272 -0.44196)
						(xy 0.19812 -0.4064) (xy 0.2032 -0.39624) (xy 0.20701 -0.38735) (xy 0.21209 -0.37719) (xy 0.2159 -0.36703)
						(xy 0.21844 -0.35687) (xy 0.22225 -0.34544) (xy 0.22352 -0.33528) (xy 0.22606 -0.32512) (xy 0.22733 -0.31369)
						(xy 0.22733 -0.30353) (xy 0.2286 -0.2921) (xy 0.22733 -0.28067) (xy 0.22733 -0.27051) (xy 0.22606 -0.25908)
						(xy 0.22352 -0.24892) (xy 0.22225 -0.23876) (xy 0.21844 -0.22733) (xy 0.2159 -0.21717) (xy 0.21209 -0.20701)
						(xy 0.20701 -0.19685) (xy 0.2032 -0.18796) (xy 0.19812 -0.1778) (xy 0.17272 -0.14224) (xy 0.1651 -0.13462)
						(xy 0.1651 0.7366) (xy 0.16256 0.76835) (xy 0.1524 0.8001) (xy 0.13716 0.82804) (xy 0.11684 0.85344)
						(xy 0.09144 0.87376) (xy 0.0635 0.889) (xy 0.03175 0.89916)
					)
					(width 0)
					(fill yes)
				)
			)
		)
		(pad "114" smd custom
			(at 4.649978 -4.106672)
			(size 0.1143 0.1143)
			(layers "F.Cu" "F.Mask" "F.Paste")
			(net "M_B_CK_DN3")
			(options
				(clearance outline)
				(anchor circle)
			)
			(primitives
				(gr_poly
					(pts
						(xy 0 0.9017) (xy -0.03175 0.89916) (xy -0.0635 0.889) (xy -0.09144 0.87376) (xy -0.11684 0.85344)
						(xy -0.13716 0.82804) (xy -0.1524 0.8001) (xy -0.16256 0.76835) (xy -0.1651 0.7366) (xy -0.1651 0.44958)
						(xy -0.17272 0.44196) (xy -0.19812 0.4064) (xy -0.2032 0.39624) (xy -0.20701 0.38735) (xy -0.21209 0.37719)
						(xy -0.2159 0.36703) (xy -0.21844 0.35687) (xy -0.22225 0.34544) (xy -0.22352 0.33528) (xy -0.22606 0.32512)
						(xy -0.22733 0.31369) (xy -0.22733 0.30353) (xy -0.2286 0.2921) (xy -0.22733 0.28067) (xy -0.22733 0.27051)
						(xy -0.22606 0.25908) (xy -0.22352 0.24892) (xy -0.22225 0.23876) (xy -0.21844 0.22733) (xy -0.2159 0.21717)
						(xy -0.21209 0.20701) (xy -0.20701 0.19685) (xy -0.2032 0.18796) (xy -0.19812 0.1778) (xy -0.17272 0.14224)
						(xy -0.1651 0.13462) (xy -0.1651 -0.7366) (xy -0.16256 -0.76835) (xy -0.1524 -0.8001) (xy -0.13716 -0.82804)
						(xy -0.11684 -0.85344) (xy -0.09144 -0.87376) (xy -0.0635 -0.889) (xy -0.03175 -0.89916) (xy 0 -0.9017)
						(xy 0.03175 -0.89916) (xy 0.0635 -0.889) (xy 0.09144 -0.87376) (xy 0.11684 -0.85344) (xy 0.13716 -0.82804)
						(xy 0.1524 -0.8001) (xy 0.16256 -0.76835) (xy 0.1651 -0.7366) (xy 0.1651 0.13462) (xy 0.17272 0.14224)
						(xy 0.19812 0.1778) (xy 0.2032 0.18796) (xy 0.20701 0.19685) (xy 0.21209 0.20701) (xy 0.2159 0.21717)
						(xy 0.21844 0.22733) (xy 0.22225 0.23876) (xy 0.22352 0.24892) (xy 0.22606 0.25908) (xy 0.22733 0.27051)
						(xy 0.22733 0.28067) (xy 0.2286 0.2921) (xy 0.22733 0.30353) (xy 0.22733 0.31369) (xy 0.22606 0.32512)
						(xy 0.22352 0.33528) (xy 0.22225 0.34544) (xy 0.21844 0.35687) (xy 0.2159 0.36703) (xy 0.21209 0.37719)
						(xy 0.20701 0.38735) (xy 0.2032 0.39624) (xy 0.19812 0.4064) (xy 0.17272 0.44196) (xy 0.1651 0.44958)
						(xy 0.1651 0.7366) (xy 0.16256 0.76835) (xy 0.1524 0.8001) (xy 0.13716 0.82804) (xy 0.11684 0.85344)
						(xy 0.09144 0.87376) (xy 0.0635 0.889) (xy 0.03175 0.89916)
					)
					(width 0)
					(fill yes)
				)
			)
		)
		(pad "115" smd custom
			(at 4.949952 4.106672)
			(size 0.1143 0.1143)
			(layers "F.Cu" "F.Mask" "F.Paste")
			(net "PV_VDDR")
			(options
				(clearance outline)
				(anchor circle)
			)
			(primitives
				(gr_poly
					(pts
						(xy 0 0.9017) (xy -0.03175 0.89916) (xy -0.0635 0.889) (xy -0.09144 0.87376) (xy -0.11684 0.85344)
						(xy -0.13716 0.82804) (xy -0.1524 0.8001) (xy -0.16256 0.76835) (xy -0.1651 0.7366) (xy -0.1651 0.11938)
						(xy -0.17272 0.11176) (xy -0.19812 0.0762) (xy -0.2032 0.06604) (xy -0.20701 0.05715) (xy -0.21209 0.04699)
						(xy -0.2159 0.03683) (xy -0.21844 0.02667) (xy -0.22225 0.01524) (xy -0.22352 0.00508) (xy -0.22606 -0.00508)
						(xy -0.22733 -0.01651) (xy -0.22733 -0.02667) (xy -0.2286 -0.0381) (xy -0.22733 -0.04953) (xy -0.22733 -0.05969)
						(xy -0.22606 -0.07112) (xy -0.22352 -0.08128) (xy -0.22225 -0.09144) (xy -0.21844 -0.10287) (xy -0.2159 -0.11303)
						(xy -0.21209 -0.12319) (xy -0.20701 -0.13335) (xy -0.2032 -0.14224) (xy -0.19812 -0.1524) (xy -0.17272 -0.18796)
						(xy -0.1651 -0.19558) (xy -0.1651 -0.7366) (xy -0.16256 -0.76835) (xy -0.1524 -0.8001) (xy -0.13716 -0.82804)
						(xy -0.11684 -0.85344) (xy -0.09144 -0.87376) (xy -0.0635 -0.889) (xy -0.03175 -0.89916) (xy 0 -0.9017)
						(xy 0.03175 -0.89916) (xy 0.0635 -0.889) (xy 0.09144 -0.87376) (xy 0.11684 -0.85344) (xy 0.13716 -0.82804)
						(xy 0.1524 -0.8001) (xy 0.16256 -0.76835) (xy 0.1651 -0.7366) (xy 0.1651 -0.19685) (xy 0.17272 -0.18923)
						(xy 0.17907 -0.18034) (xy 0.18669 -0.17145) (xy 0.19177 -0.16256) (xy 0.19812 -0.15367) (xy 0.20828 -0.13335)
						(xy 0.21971 -0.10287) (xy 0.22225 -0.09271) (xy 0.22479 -0.08128) (xy 0.22606 -0.07112) (xy 0.2286 -0.05969)
						(xy 0.2286 -0.01651) (xy 0.22606 -0.00508) (xy 0.22479 0.00508) (xy 0.22225 0.01651) (xy 0.21971 0.02667)
						(xy 0.20828 0.05715) (xy 0.19812 0.07747) (xy 0.19177 0.08636) (xy 0.18669 0.09525) (xy 0.17907 0.10414)
						(xy 0.17272 0.11303) (xy 0.1651 0.12065) (xy 0.1651 0.7366) (xy 0.16256 0.76835) (xy 0.1524 0.8001)
						(xy 0.13716 0.82804) (xy 0.11684 0.85344) (xy 0.09144 0.87376) (xy 0.0635 0.889) (xy 0.03175 0.89916)
					)
					(width 0)
					(fill yes)
				)
			)
		)
		(pad "116" smd custom
			(at 5.249926 -4.106672)
			(size 0.1143 0.1143)
			(layers "F.Cu" "F.Mask" "F.Paste")
			(net "PV_VDDR")
			(options
				(clearance outline)
				(anchor circle)
			)
			(primitives
				(gr_poly
					(pts
						(xy 0 0.9017) (xy -0.03175 0.89916) (xy -0.0635 0.889) (xy -0.09144 0.87376) (xy -0.11684 0.85344)
						(xy -0.13716 0.82804) (xy -0.1524 0.8001) (xy -0.16256 0.76835) (xy -0.1651 0.7366) (xy -0.1651 0.19685)
						(xy -0.17272 0.18923) (xy -0.17907 0.18034) (xy -0.18669 0.17145) (xy -0.19177 0.16256) (xy -0.19812 0.15367)
						(xy -0.20828 0.13335) (xy -0.21971 0.10287) (xy -0.22225 0.09271) (xy -0.22479 0.08128) (xy -0.22606 0.07112)
						(xy -0.2286 0.05969) (xy -0.2286 0.01651) (xy -0.22606 0.00508) (xy -0.22479 -0.00508) (xy -0.22225 -0.01651)
						(xy -0.21971 -0.02667) (xy -0.20828 -0.05715) (xy -0.19812 -0.07747) (xy -0.19177 -0.08636) (xy -0.18669 -0.09525)
						(xy -0.17907 -0.10414) (xy -0.17272 -0.11303) (xy -0.1651 -0.12065) (xy -0.1651 -0.7366) (xy -0.16256 -0.76835)
						(xy -0.1524 -0.8001) (xy -0.13716 -0.82804) (xy -0.11684 -0.85344) (xy -0.09144 -0.87376) (xy -0.0635 -0.889)
						(xy -0.03175 -0.89916) (xy 0 -0.9017) (xy 0.03175 -0.89916) (xy 0.0635 -0.889) (xy 0.09144 -0.87376)
						(xy 0.11684 -0.85344) (xy 0.13716 -0.82804) (xy 0.1524 -0.8001) (xy 0.16256 -0.76835) (xy 0.1651 -0.7366)
						(xy 0.1651 -0.11938) (xy 0.17272 -0.11176) (xy 0.19812 -0.0762) (xy 0.2032 -0.06604) (xy 0.20701 -0.05715)
						(xy 0.21209 -0.04699) (xy 0.2159 -0.03683) (xy 0.21844 -0.02667) (xy 0.22225 -0.01524) (xy 0.22352 -0.00508)
						(xy 0.22606 0.00508) (xy 0.22733 0.01651) (xy 0.22733 0.02667) (xy 0.2286 0.0381) (xy 0.22733 0.04953)
						(xy 0.22733 0.05969) (xy 0.22606 0.07112) (xy 0.22352 0.08128) (xy 0.22225 0.09144) (xy 0.21844 0.10287)
						(xy 0.2159 0.11303) (xy 0.21209 0.12319) (xy 0.20701 0.13335) (xy 0.2032 0.14224) (xy 0.19812 0.1524)
						(xy 0.17272 0.18796) (xy 0.1651 0.19558) (xy 0.1651 0.7366) (xy 0.16256 0.76835) (xy 0.1524 0.8001)
						(xy 0.13716 0.82804) (xy 0.11684 0.85344) (xy 0.09144 0.87376) (xy 0.0635 0.889) (xy 0.03175 0.89916)
					)
					(width 0)
					(fill yes)
				)
			)
		)
		(pad "117" smd custom
			(at 5.5499 4.106672)
			(size 0.1143 0.1143)
			(layers "F.Cu" "F.Mask" "F.Paste")
			(net "M_B_MA10")
			(options
				(clearance outline)
				(anchor circle)
			)
			(primitives
				(gr_poly
					(pts
						(xy 0 0.9017) (xy -0.03175 0.89916) (xy -0.0635 0.889) (xy -0.09144 0.87376) (xy -0.11684 0.85344)
						(xy -0.13716 0.82804) (xy -0.1524 0.8001) (xy -0.16256 0.76835) (xy -0.1651 0.7366) (xy -0.1651 -0.13462)
						(xy -0.17272 -0.14224) (xy -0.19812 -0.1778) (xy -0.2032 -0.18796) (xy -0.20701 -0.19685) (xy -0.21209 -0.20701)
						(xy -0.2159 -0.21717) (xy -0.21844 -0.22733) (xy -0.22225 -0.23876) (xy -0.22352 -0.24892) (xy -0.22606 -0.25908)
						(xy -0.22733 -0.27051) (xy -0.22733 -0.28067) (xy -0.2286 -0.2921) (xy -0.22733 -0.30353) (xy -0.22733 -0.31369)
						(xy -0.22606 -0.32512) (xy -0.22352 -0.33528) (xy -0.22225 -0.34544) (xy -0.21844 -0.35687) (xy -0.2159 -0.36703)
						(xy -0.21209 -0.37719) (xy -0.20701 -0.38735) (xy -0.2032 -0.39624) (xy -0.19812 -0.4064) (xy -0.17272 -0.44196)
						(xy -0.1651 -0.44958) (xy -0.1651 -0.7366) (xy -0.16256 -0.76835) (xy -0.1524 -0.8001) (xy -0.13716 -0.82804)
						(xy -0.11684 -0.85344) (xy -0.09144 -0.87376) (xy -0.0635 -0.889) (xy -0.03175 -0.89916) (xy 0 -0.9017)
						(xy 0.03175 -0.89916) (xy 0.0635 -0.889) (xy 0.09144 -0.87376) (xy 0.11684 -0.85344) (xy 0.13716 -0.82804)
						(xy 0.1524 -0.8001) (xy 0.16256 -0.76835) (xy 0.1651 -0.7366) (xy 0.1651 -0.44958) (xy 0.17272 -0.44196)
						(xy 0.19812 -0.4064) (xy 0.2032 -0.39624) (xy 0.20701 -0.38735) (xy 0.21209 -0.37719) (xy 0.2159 -0.36703)
						(xy 0.21844 -0.35687) (xy 0.22225 -0.34544) (xy 0.22352 -0.33528) (xy 0.22606 -0.32512) (xy 0.22733 -0.31369)
						(xy 0.22733 -0.30353) (xy 0.2286 -0.2921) (xy 0.22733 -0.28067) (xy 0.22733 -0.27051) (xy 0.22606 -0.25908)
						(xy 0.22352 -0.24892) (xy 0.22225 -0.23876) (xy 0.21844 -0.22733) (xy 0.2159 -0.21717) (xy 0.21209 -0.20701)
						(xy 0.20701 -0.19685) (xy 0.2032 -0.18796) (xy 0.19812 -0.1778) (xy 0.17272 -0.14224) (xy 0.1651 -0.13462)
						(xy 0.1651 0.7366) (xy 0.16256 0.76835) (xy 0.1524 0.8001) (xy 0.13716 0.82804) (xy 0.11684 0.85344)
						(xy 0.09144 0.87376) (xy 0.0635 0.889) (xy 0.03175 0.89916)
					)
					(width 0)
					(fill yes)
				)
			)
		)
		(pad "118" smd custom
			(at 5.849874 -4.106672)
			(size 0.1143 0.1143)
			(layers "F.Cu" "F.Mask" "F.Paste")
			(net "Net_4")
			(options
				(clearance outline)
				(anchor circle)
			)
			(primitives
				(gr_poly
					(pts
						(xy 0 0.9017) (xy -0.03175 0.89916) (xy -0.0635 0.889) (xy -0.09144 0.87376) (xy -0.11684 0.85344)
						(xy -0.13716 0.82804) (xy -0.1524 0.8001) (xy -0.16256 0.76835) (xy -0.1651 0.7366) (xy -0.1651 0.44958)
						(xy -0.17272 0.44196) (xy -0.19812 0.4064) (xy -0.2032 0.39624) (xy -0.20701 0.38735) (xy -0.21209 0.37719)
						(xy -0.2159 0.36703) (xy -0.21844 0.35687) (xy -0.22225 0.34544) (xy -0.22352 0.33528) (xy -0.22606 0.32512)
						(xy -0.22733 0.31369) (xy -0.22733 0.30353) (xy -0.2286 0.2921) (xy -0.22733 0.28067) (xy -0.22733 0.27051)
						(xy -0.22606 0.25908) (xy -0.22352 0.24892) (xy -0.22225 0.23876) (xy -0.21844 0.22733) (xy -0.2159 0.21717)
						(xy -0.21209 0.20701) (xy -0.20701 0.19685) (xy -0.2032 0.18796) (xy -0.19812 0.1778) (xy -0.17272 0.14224)
						(xy -0.1651 0.13462) (xy -0.1651 -0.7366) (xy -0.16256 -0.76835) (xy -0.1524 -0.8001) (xy -0.13716 -0.82804)
						(xy -0.11684 -0.85344) (xy -0.09144 -0.87376) (xy -0.0635 -0.889) (xy -0.03175 -0.89916) (xy 0 -0.9017)
						(xy 0.03175 -0.89916) (xy 0.0635 -0.889) (xy 0.09144 -0.87376) (xy 0.11684 -0.85344) (xy 0.13716 -0.82804)
						(xy 0.1524 -0.8001) (xy 0.16256 -0.76835) (xy 0.1651 -0.7366) (xy 0.1651 0.13462) (xy 0.17272 0.14224)
						(xy 0.19812 0.1778) (xy 0.2032 0.18796) (xy 0.20701 0.19685) (xy 0.21209 0.20701) (xy 0.2159 0.21717)
						(xy 0.21844 0.22733) (xy 0.22225 0.23876) (xy 0.22352 0.24892) (xy 0.22606 0.25908) (xy 0.22733 0.27051)
						(xy 0.22733 0.28067) (xy 0.2286 0.2921) (xy 0.22733 0.30353) (xy 0.22733 0.31369) (xy 0.22606 0.32512)
						(xy 0.22352 0.33528) (xy 0.22225 0.34544) (xy 0.21844 0.35687) (xy 0.2159 0.36703) (xy 0.21209 0.37719)
						(xy 0.20701 0.38735) (xy 0.2032 0.39624) (xy 0.19812 0.4064) (xy 0.17272 0.44196) (xy 0.1651 0.44958)
						(xy 0.1651 0.7366) (xy 0.16256 0.76835) (xy 0.1524 0.8001) (xy 0.13716 0.82804) (xy 0.11684 0.85344)
						(xy 0.09144 0.87376) (xy 0.0635 0.889) (xy 0.03175 0.89916)
					)
					(width 0)
					(fill yes)
				)
			)
		)
	)
)
